#ISCELL
  mstr_symbols cad_note *
  *
#ISCELL
  mstr_symbols intel_corp_bpage *
  *
#ISCELL
  mstr_standard offpage *
  page175_i100
#CELL
  dev_discrete cap_a *
  page175_i11
#ISCELL
  mstr_symbols gnd *
  page175_i12
#CELL
  mstr_discrete res *
  page175_i13
#ISCELL
  mstr_standard offpage *
  page175_i14
#CELL
  dev_discrete cap_a *
  page175_i19
#ISCELL
  mstr_symbols gnd *
  page175_i20
#ISCELL
  mstr_symbols p3v3_stby *
  page175_i21
#CELL
  mstr_discrete res *
  page175_i22
#ISCELL
  mstr_symbols gnd *
  page175_i27
#ISCELL
  mstr_standard offpage *
  page175_i28
#ISCELL
  mstr_symbols gnd *
  page175_i3
#CELL
  dev_discrete cap_a *
  page175_i37
#CELL
  dev_discrete cap_a *
  page175_i38
#CELL
  mstr_discrete res *
  page175_i4
#CELL
  dev_discrete cap_a *
  page175_i40
#ISCELL
  mstr_symbols gnd *
  page175_i41
#ISCELL
  mstr_symbols gnd *
  page175_i42
#ISCELL
  mstr_symbols p3v3_stby *
  page175_i43
#ISCELL
  mstr_symbols p3v3_stby *
  page175_i44
#CELL
  mstr_discrete res *
  page175_i45
#CELL
  mstr_discrete fet_n *
  page175_i49
#CELL
  mstr_discrete res *
  page175_i5
#CELL
  mstr_discrete led *
  page175_i50
#ISCELL
  mstr_standard offpage *
  page175_i52
#ISCELL
  mstr_symbols gnd *
  page175_i54
#CELL
  mstr_ttl ttl1g86 *
  page175_i57
#CELL
  mstr_discrete res *
  page175_i58
#ISCELL
  mstr_symbols p5v_stby *
  page175_i59
#ISCELL
  mstr_symbols p3v3_stby *
  page175_i6
#ISCELL
  mstr_standard offpage *
  page175_i61
#ISCELL
  mstr_standard offpage *
  page175_i62
#CELL
  mstr_discrete res *
  page175_i63
#CELL
  dev_discrete cap_a *
  page175_i64
#ISCELL
  mstr_symbols gnd *
  page175_i66
#CELL
  mstr_discrete led *
  page175_i67
#ISCELL
  mstr_symbols p3v3_stby *
  page175_i70
#ISCELL
  mstr_symbols gnd *
  page175_i71
#CELL
  mstr_misc switch_d37771002 *
  page175_i78
#ISCELL
  mstr_symbols p3v3_stby *
  page175_i85
#ISCELL
  mstr_symbols p5v_stby *
  page175_i86
#ISCELL
  mstr_standard offpage *
  page175_i87
#CELL
  mstr_misc switch_d37771002 *
  page175_i92
#CELL
  w_hdl tc7pz14fu-gp *
  page175_i93
#ISCELL
  mstr_standard offpage *
  page175_i94
#CELL
  mstr_discrete res *
  page175_i95
#ISCELL
  mstr_symbols gnd *
  page175_i96
#CELL
  w_hdl tc7pz14fu-gp *
  page175_i97
#ISCELL
  mstr_symbols gnd *
  page175_i98
#CELL
  mstr_discrete res *
  page175_i99
